(kicad_pcb
	(version 20241229)
	(generator "pcbnew")
	(generator_version "9.0")
	(general
		(thickness 1.6296)
		(legacy_teardrops no)
	)
	(paper "A3")
	(title_block
		(title "Thunderbolt to 10GbE adapter")
		(date "2026-04-21")
		(rev "1.1.0")
		(company "Antmicro Ltd")
		(comment 1 "www.antmicro.com")
		(comment 9 "footprints 365-368 of 703")
	)
	(layers
		(0 "F.Cu" signal)
		(4 "In1.Cu" signal)
		(6 "In2.Cu" signal)
		(8 "In3.Cu" signal)
		(10 "In4.Cu" signal)
		(12 "In5.Cu" signal)
		(14 "In6.Cu" signal)
		(2 "B.Cu" signal)
		(9 "F.Adhes" user "F.Adhesive")
		(11 "B.Adhes" user "B.Adhesive")
		(13 "F.Paste" user)
		(15 "B.Paste" user)
		(5 "F.SilkS" user "F.Silkscreen")
		(7 "B.SilkS" user "B.Silkscreen")
		(1 "F.Mask" user)
		(3 "B.Mask" user)
		(17 "Dwgs.User" user "User.Drawings")
		(19 "Cmts.User" user "User.Comments")
		(21 "Eco1.User" user "User.Eco1")
		(23 "Eco2.User" user "User.Eco2")
		(25 "Edge.Cuts" user)
		(27 "Margin" user)
		(31 "F.CrtYd" user "F.Courtyard")
		(29 "B.CrtYd" user "B.Courtyard")
		(35 "F.Fab" user)
		(33 "B.Fab" user)
	)
	(footprint "antmicro-footprints:C_0402_1005Metric"
		(layer "F.Cu")
		(at 138 81.75)
		(descr "Capacitor SMD 0402")
		(tags "capacitor SMD 0402")
		(property "Reference" "C269"
			(at -3.8 0.45 0)
			(layer "F.SilkS")
			(effects
				(font
					(size 0.7 0.7)
					(thickness 0.15)
				)
				(justify left bottom)
			)
		)
		(property "Value" "C_220n_16V_0402"
			(at -1.022927 2.155213 0)
			(layer "F.Fab")
			(effects
				(font
					(size 0.7 0.7)
					(thickness 0.15)
				)
				(justify left bottom)
			)
		)
		(property "Datasheet" "https://www.murata.com/products/productdetail?partno=GRM155R71C224KA12%23"
			(at 0 0 0)
			(layer "F.Fab")
			(hide yes)
			(effects
				(font
					(size 1.27 1.27)
					(thickness 0.15)
				)
			)
		)
		(property "Description" "SMD Multilayer Ceramic Capacitor, 0.22 µF, 16 V, 0402 [1005 Metric], ± 10%, X7R, GRM Series"
			(at 0 0 0)
			(layer "F.Fab")
			(hide yes)
			(effects
				(font
					(size 1.27 1.27)
					(thickness 0.15)
				)
			)
		)
		(property "MPN" "GRM155R71C224KA12D"
			(at 0 0 0)
			(unlocked yes)
			(layer "F.Fab")
			(hide yes)
			(effects
				(font
					(size 1 1)
					(thickness 0.15)
				)
			)
		)
		(property "Manufacturer" "Murata"
			(at 0 0 0)
			(unlocked yes)
			(layer "F.Fab")
			(hide yes)
			(effects
				(font
					(size 1 1)
					(thickness 0.15)
				)
			)
		)
		(property "License" "Apache-2.0"
			(at 0 0 0)
			(unlocked yes)
			(layer "F.Fab")
			(hide yes)
			(effects
				(font
					(size 1 1)
					(thickness 0.15)
				)
			)
		)
		(property "Author" "Antmicro"
			(at 0 0 0)
			(unlocked yes)
			(layer "F.Fab")
			(hide yes)
			(effects
				(font
					(size 1 1)
					(thickness 0.15)
				)
			)
		)
		(property "Val" "220n"
			(at 0 0 0)
			(unlocked yes)
			(layer "F.Fab")
			(hide yes)
			(effects
				(font
					(size 1 1)
					(thickness 0.15)
				)
			)
		)
		(property "Voltage" "16V"
			(at 0 0 0)
			(unlocked yes)
			(layer "F.Fab")
			(hide yes)
			(effects
				(font
					(size 1 1)
					(thickness 0.15)
				)
			)
		)
		(property "Dielectric" "X7R"
			(at 0 0 0)
			(unlocked yes)
			(layer "F.Fab")
			(hide yes)
			(effects
				(font
					(size 1 1)
					(thickness 0.15)
				)
			)
		)
		(sheetname "/X710-AT2 PCIe/")
		(sheetfile "x710-at2-pcie.kicad_sch")
		(attr smd)
		(fp_rect
			(start -0.925 -0.47)
			(end 0.925 0.47)
			(stroke
				(width 0.05)
				(type default)
			)
			(fill no)
			(layer "F.CrtYd")
		)
		(fp_line
			(start -0.494 -0.25)
			(end 0.504 -0.25)
			(stroke
				(width 0.15)
				(type solid)
			)
			(layer "F.Fab")
		)
		(fp_line
			(start -0.494 0.248)
			(end -0.494 -0.25)
			(stroke
				(width 0.15)
				(type solid)
			)
			(layer "F.Fab")
		)
		(fp_line
			(start 0.504 -0.25)
			(end 0.504 0.248)
			(stroke
				(width 0.15)
				(type solid)
			)
			(layer "F.Fab")
		)
		(fp_line
			(start 0.504 0.248)
			(end -0.494 0.248)
			(stroke
				(width 0.15)
				(type solid)
			)
			(layer "F.Fab")
		)
		(fp_text user "License: Apache-2.0"
			(at -0.939 5.799 0)
			(layer "F.Fab")
			(effects
				(font
					(size 0.7 0.7)
					(thickness 0.15)
				)
				(justify left bottom)
			)
		)
		(fp_text user "${REFERENCE}"
			(at -0.939 4.599 0)
			(layer "F.Fab")
			(effects
				(font
					(size 0.7 0.7)
					(thickness 0.15)
				)
				(justify left bottom)
			)
		)
		(fp_text user "Author: Antmicro"
			(at -0.939 3.399 0)
			(layer "F.Fab")
			(effects
				(font
					(size 0.7 0.7)
					(thickness 0.15)
				)
				(justify left bottom)
			)
		)
		(pad "1" smd roundrect
			(at -0.48 0)
			(size 0.59 0.64)
			(layers "F.Cu" "F.Mask" "F.Paste")
			(roundrect_rratio 0.25)
			(net 595 "/TB Controller/PCIex4.TX3-")
			(pintype "passive")
		)
		(pad "2" smd roundrect
			(at 0.48 0)
			(size 0.59 0.64)
			(layers "F.Cu" "F.Mask" "F.Paste")
			(roundrect_rratio 0.25)
			(net 34 "/X710-AT2 PCIe/PCIe_{x4}_AC.TX3-")
			(pintype "passive")
		)
	)
	(footprint "antmicro-footprints:RJ45_JTH-0024NL"
		(layer "F.Cu")
		(at 179.15 135.865 180)
		(property "Reference" "J4"
			(at -2.35 4.365 0)
			(unlocked yes)
			(layer "F.SilkS")
			(effects
				(font
					(size 0.7 0.7)
					(thickness 0.15)
				)
				(justify left bottom)
			)
		)
		(property "Value" "Bus_RJ45_JTH-0024NL"
			(at 5.06 1 180)
			(unlocked yes)
			(layer "F.Fab")
			(effects
				(font
					(size 0.7 0.7)
					(thickness 0.15)
				)
				(justify left bottom)
			)
		)
		(property "Datasheet" "https://www.mouser.com/datasheet/2/447/JTH_0024NL-3072047.pdf"
			(at 0 0 180)
			(layer "F.Fab")
			(hide yes)
			(effects
				(font
					(size 1.27 1.27)
					(thickness 0.15)
				)
			)
		)
		(property "Description" "Modular Connectors / Ethernet Connectors 1X1 TAB DOWN W/LED'S ETHERNET (NON PoE)"
			(at 0 0 180)
			(layer "F.Fab")
			(hide yes)
			(effects
				(font
					(size 1.27 1.27)
					(thickness 0.15)
				)
			)
		)
		(property "MPN" "JTH-0024NL"
			(at 0 0 180)
			(unlocked yes)
			(layer "F.Fab")
			(hide yes)
			(effects
				(font
					(size 1 1)
					(thickness 0.15)
				)
			)
		)
		(property "Manufacturer" "Pulse Electronics"
			(at 0 0 180)
			(unlocked yes)
			(layer "F.Fab")
			(hide yes)
			(effects
				(font
					(size 1 1)
					(thickness 0.15)
				)
			)
		)
		(property "Author" "Antmicro"
			(at 0 0 180)
			(unlocked yes)
			(layer "F.Fab")
			(hide yes)
			(effects
				(font
					(size 1 1)
					(thickness 0.15)
				)
			)
		)
		(property "License" "Apache-2.0"
			(at 0 0 180)
			(unlocked yes)
			(layer "F.Fab")
			(hide yes)
			(effects
				(font
					(size 1 1)
					(thickness 0.15)
				)
			)
		)
		(property ki_fp_filters "CONN18_5-2337992-8_TEC")
		(sheetname "/2xRJ45/")
		(sheetfile "2xrj45.kicad_sch")
		(attr through_hole)
		(fp_line
			(start 14 4)
			(end 14 -5.25)
			(stroke
				(width 0.1)
				(type default)
			)
			(layer "F.SilkS")
		)
		(fp_line
			(start -3.75 4)
			(end 14 4)
			(stroke
				(width 0.1)
				(type default)
			)
			(layer "F.SilkS")
		)
		(fp_line
			(start -3.75 -5.25)
			(end -3.75 4)
			(stroke
				(width 0.1)
				(type default)
			)
			(layer "F.SilkS")
		)
		(fp_rect
			(start -5.4 -20.72)
			(end 15.58 4.45)
			(stroke
				(width 0.05)
				(type solid)
			)
			(fill no)
			(layer "F.CrtYd")
		)
		(fp_text user "${REFERENCE}"
			(at -5.75 6.45 180)
			(unlocked yes)
			(layer "F.Fab")
			(effects
				(font
					(size 0.7 0.7)
					(thickness 0.15)
				)
				(justify left bottom)
			)
		)
		(fp_text user "License: Apache-2.0"
			(at -5.75 7.65 180)
			(layer "F.Fab")
			(effects
				(font
					(size 0.7 0.7)
					(thickness 0.15)
				)
				(justify left bottom)
			)
		)
		(fp_text user "Author: Antmicro"
			(at -5.75 8.85 180)
			(layer "F.Fab")
			(effects
				(font
					(size 0.7 0.7)
					(thickness 0.15)
				)
				(justify left bottom)
			)
		)
		(pad "" np_thru_hole circle
			(at 0.245 -6.6 180)
			(size 3.2 3.2)
			(drill 3.2)
			(layers "*.Cu" "*.Mask")
		)
		(pad "" np_thru_hole circle
			(at 9.895 -6.6 180)
			(size 3.2 3.2)
			(drill 3.2)
			(layers "*.Cu" "*.Mask")
		)
		(pad "1" thru_hole circle
			(at 0 0 180)
			(size 1.39 1.39)
			(drill 0.89)
			(layers "*.Cu" "*.Mask")
			(remove_unused_layers no)
			(net 134 "/2xRJ45/P1_CT")
			(pinfunction "CT3")
			(pintype "bidirectional")
		)
		(pad "2" thru_hole circle
			(at 2.03 0 180)
			(size 1.39 1.39)
			(drill 0.89)
			(layers "*.Cu" "*.Mask")
			(remove_unused_layers no)
			(net 46 "/2xRJ45/Ethernet_P1.D2-")
			(pinfunction "T2-")
			(pintype "bidirectional")
		)
		(pad "3" thru_hole circle
			(at 4.06 0 180)
			(size 1.39 1.39)
			(drill 0.89)
			(layers "*.Cu" "*.Mask")
			(remove_unused_layers no)
			(net 47 "/2xRJ45/Ethernet_P1.D2+")
			(pinfunction "T2+")
			(pintype "bidirectional")
		)
		(pad "4" thru_hole circle
			(at 6.09 0 180)
			(size 1.39 1.39)
			(drill 0.89)
			(layers "*.Cu" "*.Mask")
			(remove_unused_layers no)
			(net 48 "/2xRJ45/Ethernet_P1.D3+")
			(pinfunction "T3+")
			(pintype "bidirectional")
		)
		(pad "5" thru_hole circle
			(at 8.12 0 180)
			(size 1.39 1.39)
			(drill 0.89)
			(layers "*.Cu" "*.Mask")
			(remove_unused_layers no)
			(net 49 "/2xRJ45/Ethernet_P1.D3-")
			(pinfunction "T3-")
			(pintype "bidirectional")
		)
		(pad "6" thru_hole circle
			(at 10.15 0 180)
			(size 1.39 1.39)
			(drill 0.89)
			(layers "*.Cu" "*.Mask")
			(remove_unused_layers no)
			(net 134 "/2xRJ45/P1_CT")
			(pinfunction "CT2")
			(pintype "bidirectional")
		)
		(pad "7" thru_hole circle
			(at -1.02 2.54 180)
			(size 1.39 1.39)
			(drill 0.89)
			(layers "*.Cu" "*.Mask")
			(remove_unused_layers no)
			(net 134 "/2xRJ45/P1_CT")
			(pinfunction "CT4")
			(pintype "bidirectional")
		)
		(pad "8" thru_hole circle
			(at 1.01 2.54 180)
			(size 1.39 1.39)
			(drill 0.89)
			(layers "*.Cu" "*.Mask")
			(remove_unused_layers no)
			(net 52 "/2xRJ45/Ethernet_P1.D1+")
			(pinfunction "T1+")
			(pintype "bidirectional")
		)
		(pad "9" thru_hole circle
			(at 3.04 2.54 180)
			(size 1.39 1.39)
			(drill 0.89)
			(layers "*.Cu" "*.Mask")
			(remove_unused_layers no)
			(net 45 "/2xRJ45/Ethernet_P1.D1-")
			(pinfunction "T1-")
			(pintype "bidirectional")
		)
		(pad "10" thru_hole circle
			(at 7.11 2.54 180)
			(size 1.39 1.39)
			(drill 0.89)
			(layers "*.Cu" "*.Mask")
			(remove_unused_layers no)
			(net 51 "/2xRJ45/Ethernet_P1.D4-")
			(pinfunction "T4-")
			(pintype "bidirectional")
		)
		(pad "11" thru_hole circle
			(at 9.14 2.54 180)
			(size 1.39 1.39)
			(drill 0.89)
			(layers "*.Cu" "*.Mask")
			(remove_unused_layers no)
			(net 50 "/2xRJ45/Ethernet_P1.D4+")
			(pinfunction "T4+")
			(pintype "bidirectional")
		)
		(pad "12" thru_hole circle
			(at 11.17 2.54 180)
			(size 1.39 1.39)
			(drill 0.89)
			(layers "*.Cu" "*.Mask")
			(remove_unused_layers no)
			(net 134 "/2xRJ45/P1_CT")
			(pinfunction "CT1")
			(pintype "bidirectional")
		)
		(pad "13" thru_hole circle
			(at 12.59 -12.95 180)
			(size 1.77 1.77)
			(drill 1.27)
			(layers "*.Cu" "*.Mask")
			(remove_unused_layers no)
			(net 411 "Net-(J4-LED_GRN-)")
			(pinfunction "LED_GRN-")
			(pintype "passive")
		)
		(pad "14" thru_hole circle
			(at 12.59 -15.49 180)
			(size 1.77 1.77)
			(drill 1.27)
			(layers "*.Cu" "*.Mask")
			(remove_unused_layers no)
			(net 7 "+3V3")
			(pinfunction "LED_GRN+")
			(pintype "passive")
		)
		(pad "15" thru_hole circle
			(at -2.45 -10.41 180)
			(size 1.77 1.77)
			(drill 1.27)
			(layers "*.Cu" "*.Mask")
			(remove_unused_layers no)
			(net 407 "Net-(J4-LED_YG_Y-)")
			(pinfunction "LED_YG_Y-")
			(pintype "passive")
		)
		(pad "16" thru_hole circle
			(at -2.45 -12.95 180)
			(size 1.77 1.77)
			(drill 1.27)
			(layers "*.Cu" "*.Mask")
			(remove_unused_layers no)
			(net 7 "+3V3")
			(pinfunction "LED_COM+")
			(pintype "passive")
		)
		(pad "17" thru_hole circle
			(at -2.45 -15.49 180)
			(size 1.77 1.77)
			(drill 1.27)
			(layers "*.Cu" "*.Mask")
			(remove_unused_layers no)
			(net 409 "Net-(J4-LED_YG_G-)")
			(pinfunction "LED_YG_G-")
			(pintype "passive")
		)
		(pad "SH" thru_hole circle
			(at -3.72 -6.6 180)
			(size 2.07 2.07)
			(drill 1.57)
			(layers "*.Cu" "*.Mask")
			(remove_unused_layers no)
			(net 23 "GND")
			(pinfunction "SHIELD")
			(pintype "passive")
		)
		(pad "SH" thru_hole circle
			(at 13.86 -6.6 180)
			(size 2.07 2.07)
			(drill 1.57)
			(layers "*.Cu" "*.Mask")
			(remove_unused_layers no)
			(net 23 "GND")
			(pinfunction "SHIELD")
			(pintype "passive")
		)
	)
	(footprint "antmicro-footprints:R_0402_1005Metric"
		(layer "F.Cu")
		(at 158.355 94.054999 90)
		(descr "Resistor SMD 0402")
		(tags "resistor SMD 0402")
		(property "Reference" "R164"
			(at -19.145001 23.294999 90)
			(layer "F.SilkS")
			(effects
				(font
					(size 0.7 0.7)
					(thickness 0.15)
				)
			)
		)
		(property "Value" "R_10R_0402"
			(at -1.011843 1.772047 90)
			(layer "F.Fab")
			(effects
				(font
					(size 0.7 0.7)
					(thickness 0.15)
				)
				(justify left bottom)
			)
		)
		(property "Datasheet" "https://www.bourns.com/docs/product-datasheets/cr.pdf"
			(at 0 0 90)
			(layer "F.Fab")
			(hide yes)
			(effects
				(font
					(size 1.27 1.27)
					(thickness 0.15)
				)
			)
		)
		(property "Description" "SMD Chip Resistor, 10 ohm, ± 1%, 62.5 mW, 0402 [1005 Metric], Thick Film, General Purpose"
			(at 0 0 90)
			(layer "F.Fab")
			(hide yes)
			(effects
				(font
					(size 1.27 1.27)
					(thickness 0.15)
				)
			)
		)
		(property "MPN" "CR0402-FX-10R0GLF"
			(at 0 0 90)
			(unlocked yes)
			(layer "F.Fab")
			(hide yes)
			(effects
				(font
					(size 1 1)
					(thickness 0.15)
				)
			)
		)
		(property "Manufacturer" "Bourns"
			(at 0 0 90)
			(unlocked yes)
			(layer "F.Fab")
			(hide yes)
			(effects
				(font
					(size 1 1)
					(thickness 0.15)
				)
			)
		)
		(property "License" "Apache-2.0"
			(at 0 0 90)
			(unlocked yes)
			(layer "F.Fab")
			(hide yes)
			(effects
				(font
					(size 1 1)
					(thickness 0.15)
				)
			)
		)
		(property "Author" "Antmicro"
			(at 0 0 90)
			(unlocked yes)
			(layer "F.Fab")
			(hide yes)
			(effects
				(font
					(size 1 1)
					(thickness 0.15)
				)
			)
		)
		(property "Val" "10R"
			(at 0 0 90)
			(unlocked yes)
			(layer "F.Fab")
			(hide yes)
			(effects
				(font
					(size 1 1)
					(thickness 0.15)
				)
			)
		)
		(property "Tolerance" "1%"
			(at 0 0 90)
			(unlocked yes)
			(layer "F.Fab")
			(hide yes)
			(effects
				(font
					(size 1 1)
					(thickness 0.15)
				)
			)
		)
		(sheetname "/X710-AT2 Misc/")
		(sheetfile "x710-at2-mics.kicad_sch")
		(attr smd)
		(fp_rect
			(start -0.925 -0.47)
			(end 0.925 0.47)
			(stroke
				(width 0.05)
				(type default)
			)
			(fill no)
			(layer "F.CrtYd")
		)
		(fp_rect
			(start -0.5 -0.25)
			(end 0.5 0.25)
			(stroke
				(width 0.15)
				(type solid)
			)
			(fill no)
			(layer "F.Fab")
		)
		(fp_text user "License: Apache-2.0"
			(at -0.95 5.169 90)
			(layer "F.Fab")
			(effects
				(font
					(size 0.7 0.7)
					(thickness 0.15)
				)
				(justify left bottom)
			)
		)
		(fp_text user "Author: Antmicro"
			(at -0.95 4.169 90)
			(layer "F.Fab")
			(effects
				(font
					(size 0.7 0.7)
					(thickness 0.15)
				)
				(justify left bottom)
			)
		)
		(fp_text user "${REFERENCE}"
			(at -0.95 3.168 90)
			(layer "F.Fab")
			(effects
				(font
					(size 0.7 0.7)
					(thickness 0.15)
				)
				(justify left bottom)
			)
		)
		(pad "1" smd roundrect
			(at -0.48 0 90)
			(size 0.59 0.64)
			(layers "F.Cu" "F.Mask" "F.Paste")
			(roundrect_rratio 0.25)
			(net 58 "/X710-AT2 Misc/50MHZ_XTAL_R.+")
			(pintype "passive")
		)
		(pad "2" smd roundrect
			(at 0.48 0 90)
			(size 0.59 0.64)
			(layers "F.Cu" "F.Mask" "F.Paste")
			(roundrect_rratio 0.25)
			(net 115 "/X710-AT2 Misc/50MHZ_XTAL.+")
			(pintype "passive")
		)
	)
	(footprint "antmicro-footprints:C_0603_1608Metric"
		(layer "F.Cu")
		(at 141.49142 120.15 -90)
		(descr "Capacitor SMD 0603")
		(tags "capacitor 0603")
		(property "Reference" "C84"
			(at -1.35 -0.55 270)
			(layer "F.SilkS")
			(effects
				(font
					(size 0.7 0.7)
					(thickness 0.15)
				)
				(justify left bottom)
			)
		)
		(property "Value" "C_22u_0603"
			(at -1.42757 1.770288 270)
			(layer "F.Fab")
			(effects
				(font
					(size 0.7 0.7)
					(thickness 0.15)
				)
				(justify left bottom)
			)
		)
		(property "Datasheet" "https://www.murata.com/products/productdetail?partno=GRM188R60J226MEA0%23"
			(at 0 0 270)
			(layer "F.Fab")
			(hide yes)
			(effects
				(font
					(size 1.27 1.27)
					(thickness 0.15)
				)
			)
		)
		(property "Description" "SMD Multilayer Ceramic Capacitor, 22 µF, 6.3 V, 0603 [1608 Metric], ± 20%, X5R, GRM Series"
			(at 0 0 270)
			(layer "F.Fab")
			(hide yes)
			(effects
				(font
					(size 1.27 1.27)
					(thickness 0.15)
				)
			)
		)
		(property "MPN" "GRM188R60J226MEA0D"
			(at 0 0 270)
			(unlocked yes)
			(layer "F.Fab")
			(hide yes)
			(effects
				(font
					(size 1 1)
					(thickness 0.15)
				)
			)
		)
		(property "Manufacturer" "Murata"
			(at 0 0 270)
			(unlocked yes)
			(layer "F.Fab")
			(hide yes)
			(effects
				(font
					(size 1 1)
					(thickness 0.15)
				)
			)
		)
		(property "License" "Apache-2.0"
			(at 0 0 270)
			(unlocked yes)
			(layer "F.Fab")
			(hide yes)
			(effects
				(font
					(size 1 1)
					(thickness 0.15)
				)
			)
		)
		(property "Val" "22u"
			(at 0 0 270)
			(unlocked yes)
			(layer "F.Fab")
			(hide yes)
			(effects
				(font
					(size 1 1)
					(thickness 0.15)
				)
			)
		)
		(property "Voltage" ""
			(at 0 0 270)
			(unlocked yes)
			(layer "F.Fab")
			(hide yes)
			(effects
				(font
					(size 1 1)
					(thickness 0.15)
				)
			)
		)
		(property "Dielectric" ""
			(at 0 0 270)
			(unlocked yes)
			(layer "F.Fab")
			(hide yes)
			(effects
				(font
					(size 1 1)
					(thickness 0.15)
				)
			)
		)
		(property "Author" "Antmicro"
			(at 0 0 270)
			(unlocked yes)
			(layer "F.Fab")
			(hide yes)
			(effects
				(font
					(size 1 1)
					(thickness 0.15)
				)
			)
		)
		(sheetname "/TB Controller - Power/")
		(sheetfile "tb-power.kicad_sch")
		(attr smd)
		(fp_line
			(start -0.15 0.4)
			(end 0.15 0.4)
			(stroke
				(width 0.15)
				(type solid)
			)
			(layer "F.SilkS")
		)
		(fp_line
			(start -0.15 -0.4)
			(end 0.15 -0.4)
			(stroke
				(width 0.15)
				(type solid)
			)
			(layer "F.SilkS")
		)
		(fp_rect
			(start -1.25 -0.65)
			(end 1.25 0.65)
			(stroke
				(width 0.05)
				(type solid)
			)
			(fill no)
			(layer "F.CrtYd")
		)
		(fp_rect
			(start -0.8 -0.4)
			(end 0.8 0.4)
			(stroke
				(width 0.15)
				(type solid)
			)
			(fill no)
			(layer "F.Fab")
		)
		(fp_text user "License: Apache-2.0"
			(at -1.682 5.895 270)
			(layer "F.Fab")
			(effects
				(font
					(size 0.7 0.7)
					(thickness 0.15)
				)
				(justify left bottom)
			)
		)
		(fp_text user "${REFERENCE}"
			(at -1.682 3.895 270)
			(layer "F.Fab")
			(effects
				(font
					(size 0.7 0.7)
					(thickness 0.15)
				)
				(justify left bottom)
			)
		)
		(fp_text user "Author: Antmicro"
			(at -1.682 4.894 270)
			(layer "F.Fab")
			(effects
				(font
					(size 0.7 0.7)
					(thickness 0.15)
				)
				(justify left bottom)
			)
		)
		(pad "1" smd roundrect
			(at -0.7 0 270)
			(size 0.8 1)
			(layers "F.Cu" "F.Mask" "F.Paste")
			(roundrect_rratio 0.2)
			(net 23 "GND")
			(pintype "passive")
		)
		(pad "2" smd roundrect
			(at 0.7 0 270)
			(size 0.8 1)
			(layers "F.Cu" "F.Mask" "F.Paste")
			(roundrect_rratio 0.2)
			(net 68 "/TB Controller - Power/VCC_0P9")
			(pintype "passive")
		)
	)
)
